# BARRELEYE-G2-SXM2 RISER BOARD-EVT-X00-BOM-X01-20171102_Final.xls.xlsx — TLA (bom)
| FOXCONN TECHNOLOGY GROUP |  |  |  |  |  |  |  |  |  |
| BILL OF MATERIAL |  |  |  |  |  |  |  |  |  |
| AA P/N | 1A42NC600-600-G | CUSTOMER | <name> | Customer P/N | N/A | Product Code |  |  |  |
| PWA P/N |  | PWA DESCRIPTION | SXM2 Riser board for GV100 |  |  | PWA REV | EVT-X00 | Prepared By SE |  |
| Item | FOXCONN P/N | Customer P/N | Part Description | Manufacturer  Full Name | Manufacturer  Part Number | Qty | RoHS Status | Location | Remark |
| 1 | 7J-004-938 |  | L6 LABEL ( 12.7*11.1mm) | FOXCONN / EPD1 | 7J-004-938 | 1 | G |  |  |
| 2 | TBD |  | TBD | TBD | TBD | TBD | G |  | The design is in progress |
